(kicad_pcb
	(version 20260206)
	(generator "pcbnew")
	(generator_version "10.0")
	(general
		(thickness 1.6)
		(legacy_teardrops no)
	)
	(paper "A4")
	(title_block
		(title "04192023_DAF0TMB3IC0_F0TG_MB_C_brd_V02_OCP.brd")
		(comment 1 "Grand Teton / footprints 3505-3507 of 8354")
	)
	(layers
		(0 "F.Cu" signal "TOP")
		(4 "In1.Cu" signal "GND")
		(6 "In2.Cu" signal "IN1")
		(8 "In3.Cu" signal "GND1")
		(10 "In4.Cu" signal "IN2")
		(12 "In5.Cu" signal "GND2")
		(14 "In6.Cu" signal "IN3")
		(16 "In7.Cu" signal "GND3")
		(18 "In8.Cu" signal "VCC")
		(20 "In9.Cu" signal "VCC1")
		(22 "In10.Cu" signal "GND4")
		(24 "In11.Cu" signal "IN4")
		(26 "In12.Cu" signal "GND5")
		(28 "In13.Cu" signal "IN5")
		(30 "In14.Cu" signal "GND6")
		(32 "In15.Cu" signal "IN6")
		(34 "In16.Cu" signal "GND7")
		(2 "B.Cu" signal "BOTTOM")
		(9 "F.Adhes" user "F.Adhesive")
		(11 "B.Adhes" user "B.Adhesive")
		(13 "F.Paste" user "Package Geometry/Pastemask Top")
		(15 "B.Paste" user "Package Geometry/Pastemask Bottom")
		(5 "F.SilkS" user "Ref Des/Silkscreen Top")
		(7 "B.SilkS" user "Ref Des/Silkscreen Bottom")
		(1 "F.Mask" user "Board Geometry/Soldermask Top")
		(3 "B.Mask" user "Board Geometry/Soldermask Bottom")
		(17 "Dwgs.User" user "User.Drawings")
		(19 "Cmts.User" user "User.Comments")
		(21 "Eco1.User" user "User.Eco1")
		(23 "Eco2.User" user "User.Eco2")
		(25 "Edge.Cuts" user "Board Geometry/Outline")
		(27 "Margin" user)
		(31 "F.CrtYd" user "Package Geometry/Place Bound Top")
		(29 "B.CrtYd" user "Package Geometry/Place Bound Bottom")
		(35 "F.Fab" user "Ref Des/Assembly Top")
		(33 "B.Fab" user "Ref Des/Assembly Bottom")
	)
	(footprint ""
		(layer "F.Cu")
		(at 376.35815 -180.078634 -90)
		(property "Reference" "PC476"
			(at 0 0 270)
			(layer "F.SilkS")
			(hide yes)
			(effects
				(font
					(size 1.27 1.27)
				)
			)
		)
		(property "Value" ""
			(at 0 0 270)
			(layer "F.Fab")
			(effects
				(font
					(size 1.27 1.27)
				)
			)
		)
		(duplicate_pad_numbers_are_jumpers no)
		(fp_line
			(start -0.7874 0.4064)
			(end -0.7874 -0.4064)
			(stroke
				(width 0.1524)
				(type default)
			)
			(layer "F.SilkS")
		)
		(fp_line
			(start -0.210566 0.4064)
			(end -0.7874 0.4064)
			(stroke
				(width 0.1524)
				(type default)
			)
			(layer "F.SilkS")
		)
		(fp_line
			(start 0.7874 0.4064)
			(end 0.399034 0.4064)
			(stroke
				(width 0.1524)
				(type default)
			)
			(layer "F.SilkS")
		)
		(fp_line
			(start -0.7874 -0.4064)
			(end 0.7874 -0.4064)
			(stroke
				(width 0.1524)
				(type default)
			)
			(layer "F.SilkS")
		)
		(fp_line
			(start 0.7874 -0.4064)
			(end 0.7874 0.4064)
			(stroke
				(width 0.1524)
				(type default)
			)
			(layer "F.SilkS")
		)
		(fp_line
			(start -0.67945 0.3048)
			(end -0.67945 -0.305054)
			(stroke
				(width 0.1)
				(type default)
			)
			(layer "F.Fab")
		)
		(fp_line
			(start -0.12065 0.3048)
			(end -0.67945 0.3048)
			(stroke
				(width 0.1)
				(type default)
			)
			(layer "F.Fab")
		)
		(fp_line
			(start 0.120396 0.3048)
			(end 0.120396 0.2794)
			(stroke
				(width 0.1)
				(type default)
			)
			(layer "F.Fab")
		)
		(fp_line
			(start 0.67945 0.3048)
			(end 0.120396 0.3048)
			(stroke
				(width 0.1)
				(type default)
			)
			(layer "F.Fab")
		)
		(fp_line
			(start -0.12065 0.2794)
			(end -0.12065 0.3048)
			(stroke
				(width 0.1)
				(type default)
			)
			(layer "F.Fab")
		)
		(fp_line
			(start 0.120396 0.2794)
			(end -0.12065 0.2794)
			(stroke
				(width 0.1)
				(type default)
			)
			(layer "F.Fab")
		)
		(fp_line
			(start -0.12065 -0.2794)
			(end 0.12065 -0.2794)
			(stroke
				(width 0.1)
				(type default)
			)
			(layer "F.Fab")
		)
		(fp_line
			(start 0.12065 -0.2794)
			(end 0.12065 -0.3048)
			(stroke
				(width 0.1)
				(type default)
			)
			(layer "F.Fab")
		)
		(fp_line
			(start 0.12065 -0.3048)
			(end 0.67945 -0.3048)
			(stroke
				(width 0.1)
				(type default)
			)
			(layer "F.Fab")
		)
		(fp_line
			(start 0.67945 -0.3048)
			(end 0.67945 0.3048)
			(stroke
				(width 0.1)
				(type default)
			)
			(layer "F.Fab")
		)
		(fp_line
			(start -0.67945 -0.305054)
			(end -0.12065 -0.305054)
			(stroke
				(width 0.1)
				(type default)
			)
			(layer "F.Fab")
		)
		(fp_line
			(start -0.12065 -0.305054)
			(end -0.12065 -0.2794)
			(stroke
				(width 0.1)
				(type default)
			)
			(layer "F.Fab")
		)
		(pad "1" smd circle
			(at -0.40005 0 270)
			(size 0 0)
			(layers "F.Cu" "F.Mask" "F.Paste")
			(net "PVDDCR_CPU0_P0_VCC2")
		)
		(pad "2" smd circle
			(at 0.40005 0 270)
			(size 0 0)
			(layers "F.Cu" "F.Mask" "F.Paste")
			(net "GND")
		)
	)
	(footprint ""
		(layer "F.Cu")
		(at 48.523652 -400.419316 -90)
		(property "Reference" "C229"
			(at 0 0 270)
			(layer "F.SilkS")
			(hide yes)
			(effects
				(font
					(size 1.27 1.27)
				)
			)
		)
		(property "Value" ""
			(at 0 0 270)
			(layer "F.Fab")
			(effects
				(font
					(size 1.27 1.27)
				)
			)
		)
		(duplicate_pad_numbers_are_jumpers no)
		(fp_line
			(start -1.524 0.762)
			(end -1.524 -0.762)
			(stroke
				(width 0.1524)
				(type default)
			)
			(layer "F.SilkS")
		)
		(fp_line
			(start 1.524 0.762)
			(end -1.524 0.762)
			(stroke
				(width 0.1524)
				(type default)
			)
			(layer "F.SilkS")
		)
		(fp_line
			(start -1.524 -0.762)
			(end 1.524 -0.762)
			(stroke
				(width 0.1524)
				(type default)
			)
			(layer "F.SilkS")
		)
		(fp_line
			(start 1.524 -0.762)
			(end 1.524 0.762)
			(stroke
				(width 0.1524)
				(type default)
			)
			(layer "F.SilkS")
		)
		(fp_line
			(start -1.1049 0.724916)
			(end 1.1049 0.724916)
			(stroke
				(width 0.1)
				(type default)
			)
			(layer "F.Fab")
		)
		(fp_line
			(start 1.1049 0.724916)
			(end 1.1049 -0.724916)
			(stroke
				(width 0.1)
				(type default)
			)
			(layer "F.Fab")
		)
		(fp_line
			(start -1.1049 -0.724916)
			(end -1.1049 0.724916)
			(stroke
				(width 0.1)
				(type default)
			)
			(layer "F.Fab")
		)
		(fp_line
			(start 1.1049 -0.724916)
			(end -1.1049 -0.724916)
			(stroke
				(width 0.1)
				(type default)
			)
			(layer "F.Fab")
		)
		(pad "1" smd rect
			(at -0.889 0 90)
			(size 1.016 1.27)
			(layers "F.Cu" "F.Mask" "F.Paste")
			(net "P0V9_CPU1_RT_2D")
		)
		(pad "2" smd rect
			(at 0.889 0 90)
			(size 1.016 1.27)
			(layers "F.Cu" "F.Mask" "F.Paste")
			(net "GND")
		)
	)
	(footprint ""
		(layer "F.Cu")
		(at 127.121666 -408.517344 -90)
		(property "Reference" "C6702"
			(at 0 0 270)
			(layer "F.SilkS")
			(hide yes)
			(effects
				(font
					(size 1.27 1.27)
				)
			)
		)
		(property "Value" ""
			(at 0 0 270)
			(layer "F.Fab")
			(effects
				(font
					(size 1.27 1.27)
				)
			)
		)
		(duplicate_pad_numbers_are_jumpers no)
		(fp_line
			(start -0.299974 0.150114)
			(end -0.299974 -0.150114)
			(stroke
				(width 0.1)
				(type default)
			)
			(layer "F.Fab")
		)
		(fp_line
			(start 0.299974 0.150114)
			(end -0.299974 0.150114)
			(stroke
				(width 0.1)
				(type default)
			)
			(layer "F.Fab")
		)
		(fp_line
			(start -0.299974 -0.150114)
			(end 0.299974 -0.150114)
			(stroke
				(width 0.1)
				(type default)
			)
			(layer "F.Fab")
		)
		(fp_line
			(start 0.299974 -0.150114)
			(end 0.299974 0.150114)
			(stroke
				(width 0.1)
				(type default)
			)
			(layer "F.Fab")
		)
		(pad "1" smd rect
			(at -0.2667 0 270)
			(size 0.3048 0.381)
			(layers "F.Cu" "F.Mask" "F.Paste")
			(net "P5E_CPU1_P2_TX_BUF_C_DN<4>")
		)
		(pad "2" smd rect
			(at 0.2667 0 270)
			(size 0.3048 0.381)
			(layers "F.Cu" "F.Mask" "F.Paste")
			(net "P5E_CPU1_P2_TX_BUF_DN<4>")
		)
	)
)
